(kicad_pcb
	(version 20260206)
	(generator "pcbnew")
	(generator_version "10.0")
	(general
		(thickness 1.6)
		(legacy_teardrops no)
	)
	(paper "A4")
	(title_block
		(title "Wiwynn_Tioga_Pass_MB.brd")
		(comment 1 "Tioga Pass / footprints 4709-4715 of 4770")
	)
	(layers
		(0 "F.Cu" signal "TOP")
		(4 "In1.Cu" signal "L2GND")
		(6 "In2.Cu" signal "L3")
		(8 "In3.Cu" signal "L4GND")
		(10 "In4.Cu" signal "L5")
		(12 "In5.Cu" signal "L6GND")
		(14 "In6.Cu" signal "L7VCC")
		(16 "In7.Cu" signal "L8VCC")
		(18 "In8.Cu" signal "L9GND")
		(20 "In9.Cu" signal "L10")
		(22 "In10.Cu" signal "L11GND")
		(24 "In11.Cu" signal "L12")
		(26 "In12.Cu" signal "L13GND")
		(2 "B.Cu" signal "BOTTOM")
		(9 "F.Adhes" user "F.Adhesive")
		(11 "B.Adhes" user "B.Adhesive")
		(13 "F.Paste" user "Package Geometry/Pastemask Top")
		(15 "B.Paste" user "Package Geometry/Pastemask Bottom")
		(5 "F.SilkS" user "Ref Des/Silkscreen Top")
		(7 "B.SilkS" user "Ref Des/Silkscreen Bottom")
		(1 "F.Mask" user "Board Geometry/Soldermask Top")
		(3 "B.Mask" user "Board Geometry/Soldermask Bottom")
		(17 "Dwgs.User" user "User.Drawings")
		(19 "Cmts.User" user "User.Comments")
		(21 "Eco1.User" user "User.Eco1")
		(23 "Eco2.User" user "User.Eco2")
		(25 "Edge.Cuts" user "Board Geometry/Outline")
		(27 "Margin" user)
		(31 "F.CrtYd" user "Package Geometry/Place Bound Top")
		(29 "B.CrtYd" user "Package Geometry/Place Bound Bottom")
		(35 "F.Fab" user "Ref Des/Assembly Top")
		(33 "B.Fab" user "Ref Des/Assembly Bottom")
	)
	(footprint ""
		(layer "B.Cu")
		(at 278.7142 -29.337 90)
		(property "Reference" "SH4U1"
			(at 0 0 90)
			(layer "B.SilkS")
			(hide yes)
			(effects
				(font
					(size 1.27 1.27)
				)
				(justify mirror)
			)
		)
		(property "Value" ""
			(at 0 0 90)
			(layer "B.Fab")
			(effects
				(font
					(size 1.27 1.27)
				)
				(justify mirror)
			)
		)
		(duplicate_pad_numbers_are_jumpers no)
		(fp_poly
			(pts
				(xy 0.1651 -0.0508) (xy 0.1651 0.5842) (xy -0.1651 0.5842) (xy -0.1651 -0.0508)
			)
			(stroke
				(width 0)
				(type default)
			)
			(fill no)
			(layer "B.CrtYd")
		)
		(fp_line
			(start 0.1651 -0.0508)
			(end -0.1651 -0.0508)
			(stroke
				(width 0.1)
				(type default)
			)
			(layer "B.Fab")
		)
		(fp_line
			(start -0.1651 -0.0508)
			(end -0.1651 0.5842)
			(stroke
				(width 0.1)
				(type default)
			)
			(layer "B.Fab")
		)
		(fp_line
			(start 0.1651 0.5842)
			(end 0.1651 -0.0508)
			(stroke
				(width 0.1)
				(type default)
			)
			(layer "B.Fab")
		)
		(fp_line
			(start -0.1651 0.5842)
			(end 0.1651 0.5842)
			(stroke
				(width 0.1)
				(type default)
			)
			(layer "B.Fab")
		)
		(pad "1" smd custom
			(at 0 0 90)
			(size 0.0762 0.0762)
			(layers "B.Cu" "B.Mask" "B.Paste")
			(net "VSENSE_PVDDQ_ABC_N")
			(options
				(clearance outline)
				(anchor circle)
			)
			(primitives
				(gr_poly
					(pts
						(arc
							(start -0.1524 0.10795)
							(mid -0.098518 0.130268)
							(end -0.0762 0.18415)
						)
						(xy -0.0762 0.22225) (xy 0.0762 0.22225)
						(arc
							(start 0.0762 0.18415)
							(mid 0.098518 0.130268)
							(end 0.1524 0.10795)
						)
						(xy 0.1524 -0.22225) (xy -0.1524 -0.22225)
					)
					(width 0)
					(fill yes)
				)
			)
		)
		(pad "2" smd custom
			(at 0 0.5334 270)
			(size 0.0762 0.0762)
			(layers "B.Cu" "B.Mask" "B.Paste")
			(net "GND")
			(options
				(clearance outline)
				(anchor circle)
			)
			(primitives
				(gr_poly
					(pts
						(arc
							(start -0.1524 0.10795)
							(mid -0.098518 0.130268)
							(end -0.0762 0.18415)
						)
						(xy -0.0762 0.22225) (xy 0.0762 0.22225)
						(arc
							(start 0.0762 0.18415)
							(mid 0.098518 0.130268)
							(end 0.1524 0.10795)
						)
						(xy 0.1524 -0.22225) (xy -0.1524 -0.22225)
					)
					(width 0)
					(fill yes)
				)
			)
		)
	)
	(footprint ""
		(layer "B.Cu")
		(at 13.97 -41.402 -90)
		(property "Reference" "R9R10"
			(at 0 0 90)
			(layer "B.SilkS")
			(hide yes)
			(effects
				(font
					(size 1.27 1.27)
				)
				(justify mirror)
			)
		)
		(property "Value" ""
			(at 0 0 90)
			(layer "B.Fab")
			(effects
				(font
					(size 1.27 1.27)
				)
				(justify mirror)
			)
		)
		(duplicate_pad_numbers_are_jumpers no)
		(fp_poly
			(pts
				(xy 0.2794 -0.1016) (xy -0.2794 -0.1016) (xy -0.2794 0.9906) (xy 0.2794 0.9906)
			)
			(stroke
				(width 0)
				(type default)
			)
			(fill no)
			(layer "B.CrtYd")
		)
		(fp_line
			(start -0.2794 0.9906)
			(end -0.2794 -0.1016)
			(stroke
				(width 0.1)
				(type default)
			)
			(layer "B.Fab")
		)
		(fp_line
			(start 0.2794 0.9906)
			(end -0.2794 0.9906)
			(stroke
				(width 0.1)
				(type default)
			)
			(layer "B.Fab")
		)
		(fp_line
			(start -0.2794 -0.1016)
			(end 0.2794 -0.1016)
			(stroke
				(width 0.1)
				(type default)
			)
			(layer "B.Fab")
		)
		(fp_line
			(start 0.2794 -0.1016)
			(end 0.2794 0.9906)
			(stroke
				(width 0.1)
				(type default)
			)
			(layer "B.Fab")
		)
		(pad "1" smd rect
			(at 0 0 90)
			(size 0.508 0.508)
			(layers "B.Cu" "B.Mask" "B.Paste")
			(net "FAN_TACH1")
		)
		(pad "2" smd rect
			(at 0 0.889 90)
			(size 0.508 0.508)
			(layers "B.Cu" "B.Mask" "B.Paste")
			(net "FAN_TACH1_R")
		)
		(zone
			(layer "B.Cu")
			(hatch none 0.5)
			(connect_pads
				(clearance 0)
			)
			(min_thickness 0.25)
			(keepout
				(tracks not_allowed)
				(vias allowed)
				(pads allowed)
				(copperpour not_allowed)
				(footprints allowed)
			)
			(placement
				(enabled no)
				(sheetname "")
			)
			(fill
				(thermal_gap 0.5)
				(thermal_bridge_width 0.5)
				(island_removal_mode 0)
			)
			(polygon
				(pts
					(xy 13.335 -41.148) (xy 13.335 -41.656) (xy 13.716 -41.656) (xy 13.716 -41.148)
				)
			)
		)
		(zone
			(layer "B.Cu")
			(hatch none 0.5)
			(connect_pads
				(clearance 0)
			)
			(min_thickness 0.25)
			(keepout
				(tracks allowed)
				(vias not_allowed)
				(pads allowed)
				(copperpour not_allowed)
				(footprints allowed)
			)
			(placement
				(enabled no)
				(sheetname "")
			)
			(fill
				(thermal_gap 0.5)
				(thermal_bridge_width 0.5)
				(island_removal_mode 0)
			)
			(polygon
				(pts
					(xy 13.716 -41.148) (xy 13.716 -41.656) (xy 13.335 -41.656) (xy 13.335 -41.148)
				)
			)
		)
	)
	(footprint ""
		(layer "B.Cu")
		(at 477.774 -34.0995)
		(property "Reference" "C2T37"
			(at 0 0 0)
			(layer "B.SilkS")
			(hide yes)
			(effects
				(font
					(size 1.27 1.27)
				)
				(justify mirror)
			)
		)
		(property "Value" ""
			(at 0 0 0)
			(layer "B.Fab")
			(effects
				(font
					(size 1.27 1.27)
				)
				(justify mirror)
			)
		)
		(duplicate_pad_numbers_are_jumpers no)
		(fp_poly
			(pts
				(xy -0.3048 -0.1016) (xy -0.3048 0.9906) (xy 0.3048 0.9906) (xy 0.3048 -0.1016)
			)
			(stroke
				(width 0)
				(type default)
			)
			(fill no)
			(layer "B.CrtYd")
		)
		(fp_line
			(start -0.3048 -0.1016)
			(end 0.3048 -0.1016)
			(stroke
				(width 0.1)
				(type default)
			)
			(layer "B.Fab")
		)
		(fp_line
			(start -0.3048 0.9906)
			(end -0.3048 -0.1016)
			(stroke
				(width 0.1)
				(type default)
			)
			(layer "B.Fab")
		)
		(fp_line
			(start 0.3048 -0.1016)
			(end 0.3048 0.9906)
			(stroke
				(width 0.1)
				(type default)
			)
			(layer "B.Fab")
		)
		(fp_line
			(start 0.3048 0.9906)
			(end -0.3048 0.9906)
			(stroke
				(width 0.1)
				(type default)
			)
			(layer "B.Fab")
		)
		(pad "1" smd rect
			(at 0 0 180)
			(size 0.508 0.508)
			(layers "B.Cu" "B.Mask" "B.Paste")
			(net "P3V3_STBY_MNG_RMII")
		)
		(pad "2" smd rect
			(at 0 0.889 180)
			(size 0.508 0.508)
			(layers "B.Cu" "B.Mask" "B.Paste")
			(net "GND")
		)
		(zone
			(layer "B.Cu")
			(hatch none 0.5)
			(connect_pads
				(clearance 0)
			)
			(min_thickness 0.25)
			(keepout
				(tracks allowed)
				(vias not_allowed)
				(pads allowed)
				(copperpour not_allowed)
				(footprints allowed)
			)
			(placement
				(enabled no)
				(sheetname "")
			)
			(fill
				(thermal_gap 0.5)
				(thermal_bridge_width 0.5)
				(island_removal_mode 0)
			)
			(polygon
				(pts
					(xy 478.028 -33.8455) (xy 477.52 -33.8455) (xy 477.52 -33.4645) (xy 478.028 -33.4645)
				)
			)
		)
		(zone
			(layer "B.Cu")
			(hatch none 0.5)
			(connect_pads
				(clearance 0)
			)
			(min_thickness 0.25)
			(keepout
				(tracks not_allowed)
				(vias allowed)
				(pads allowed)
				(copperpour not_allowed)
				(footprints allowed)
			)
			(placement
				(enabled no)
				(sheetname "")
			)
			(fill
				(thermal_gap 0.5)
				(thermal_bridge_width 0.5)
				(island_removal_mode 0)
			)
			(polygon
				(pts
					(xy 478.028 -33.4645) (xy 477.52 -33.4645) (xy 477.52 -33.8455) (xy 478.028 -33.8455)
				)
			)
		)
	)
	(footprint ""
		(layer "B.Cu")
		(at 260.6802 -26.475182 -90)
		(property "Reference" "C5T3"
			(at 0 0 90)
			(layer "B.SilkS")
			(hide yes)
			(effects
				(font
					(size 1.27 1.27)
				)
				(justify mirror)
			)
		)
		(property "Value" ""
			(at 0 0 90)
			(layer "B.Fab")
			(effects
				(font
					(size 1.27 1.27)
				)
				(justify mirror)
			)
		)
		(duplicate_pad_numbers_are_jumpers no)
		(fp_rect
			(start 0.500126 1.598422)
			(end -0.500126 -0.201422)
			(stroke
				(width 0)
				(type default)
			)
			(fill no)
			(layer "B.CrtYd")
		)
		(fp_line
			(start -0.500126 1.598422)
			(end 0.500126 1.598422)
			(stroke
				(width 0.1)
				(type default)
			)
			(layer "B.Fab")
		)
		(fp_line
			(start 0.500126 1.598422)
			(end 0.500126 -0.201422)
			(stroke
				(width 0.1)
				(type default)
			)
			(layer "B.Fab")
		)
		(fp_line
			(start -0.500126 -0.201422)
			(end -0.500126 1.598422)
			(stroke
				(width 0.1)
				(type default)
			)
			(layer "B.Fab")
		)
		(fp_line
			(start 0.500126 -0.201422)
			(end -0.500126 -0.201422)
			(stroke
				(width 0.1)
				(type default)
			)
			(layer "B.Fab")
		)
		(pad "1" smd rect
			(at 0 0 180)
			(size 0.889 0.9906)
			(layers "B.Cu" "B.Mask" "B.Paste")
			(net "PVTT_ABC")
		)
		(pad "2" smd rect
			(at 0 1.397 180)
			(size 0.889 0.9906)
			(layers "B.Cu" "B.Mask" "B.Paste")
			(net "GND")
		)
		(zone
			(layer "B.Cu")
			(hatch none 0.5)
			(connect_pads
				(clearance 0)
			)
			(min_thickness 0.25)
			(keepout
				(tracks not_allowed)
				(vias allowed)
				(pads allowed)
				(copperpour not_allowed)
				(footprints allowed)
			)
			(placement
				(enabled no)
				(sheetname "")
			)
			(fill
				(thermal_gap 0.5)
				(thermal_bridge_width 0.5)
				(island_removal_mode 0)
			)
			(polygon
				(pts
					(xy 259.7277 -25.979882) (xy 260.2357 -25.979882) (xy 260.2357 -26.970482) (xy 259.7277 -26.970482)
				)
			)
		)
		(zone
			(layer "B.Cu")
			(hatch none 0.5)
			(connect_pads
				(clearance 0)
			)
			(min_thickness 0.25)
			(keepout
				(tracks allowed)
				(vias not_allowed)
				(pads allowed)
				(copperpour not_allowed)
				(footprints allowed)
			)
			(placement
				(enabled no)
				(sheetname "")
			)
			(fill
				(thermal_gap 0.5)
				(thermal_bridge_width 0.5)
				(island_removal_mode 0)
			)
			(polygon
				(pts
					(xy 259.7277 -25.979882) (xy 260.2357 -25.979882) (xy 260.2357 -26.970482) (xy 259.7277 -26.970482)
				)
			)
		)
	)
	(footprint ""
		(layer "B.Cu")
		(at 101.3968 -8.1534 90)
		(property "Reference" "C8U3"
			(at -1.848866 0.752348 90)
			(unlocked yes)
			(layer "B.SilkS")
			(effects
				(font
					(size 1.27 0.9652)
					(thickness 0.1524)
				)
				(justify mirror)
			)
		)
		(property "Value" ""
			(at 0 0 90)
			(layer "B.Fab")
			(effects
				(font
					(size 1.27 1.27)
				)
				(justify mirror)
			)
		)
		(duplicate_pad_numbers_are_jumpers no)
		(fp_rect
			(start 0.500126 1.598422)
			(end -0.500126 -0.201422)
			(stroke
				(width 0)
				(type default)
			)
			(fill no)
			(layer "B.CrtYd")
		)
		(fp_line
			(start 0.500126 -0.201422)
			(end -0.500126 -0.201422)
			(stroke
				(width 0.1)
				(type default)
			)
			(layer "B.Fab")
		)
		(fp_line
			(start -0.500126 -0.201422)
			(end -0.500126 1.598422)
			(stroke
				(width 0.1)
				(type default)
			)
			(layer "B.Fab")
		)
		(fp_line
			(start 0.500126 1.598422)
			(end 0.500126 -0.201422)
			(stroke
				(width 0.1)
				(type default)
			)
			(layer "B.Fab")
		)
		(fp_line
			(start -0.500126 1.598422)
			(end 0.500126 1.598422)
			(stroke
				(width 0.1)
				(type default)
			)
			(layer "B.Fab")
		)
		(pad "1" smd rect
			(at 0 0)
			(size 0.889 0.9906)
			(layers "B.Cu" "B.Mask" "B.Paste")
			(net "PVDDQ_GHJ")
		)
		(pad "2" smd rect
			(at 0 1.397)
			(size 0.889 0.9906)
			(layers "B.Cu" "B.Mask" "B.Paste")
			(net "GND")
		)
		(zone
			(layer "B.Cu")
			(hatch none 0.5)
			(connect_pads
				(clearance 0)
			)
			(min_thickness 0.25)
			(keepout
				(tracks allowed)
				(vias not_allowed)
				(pads allowed)
				(copperpour not_allowed)
				(footprints allowed)
			)
			(placement
				(enabled no)
				(sheetname "")
			)
			(fill
				(thermal_gap 0.5)
				(thermal_bridge_width 0.5)
				(island_removal_mode 0)
			)
			(polygon
				(pts
					(xy 102.3493 -8.6487) (xy 101.8413 -8.6487) (xy 101.8413 -7.6581) (xy 102.3493 -7.6581)
				)
			)
		)
		(zone
			(layer "B.Cu")
			(hatch none 0.5)
			(connect_pads
				(clearance 0)
			)
			(min_thickness 0.25)
			(keepout
				(tracks not_allowed)
				(vias allowed)
				(pads allowed)
				(copperpour not_allowed)
				(footprints allowed)
			)
			(placement
				(enabled no)
				(sheetname "")
			)
			(fill
				(thermal_gap 0.5)
				(thermal_bridge_width 0.5)
				(island_removal_mode 0)
			)
			(polygon
				(pts
					(xy 102.3493 -8.6487) (xy 101.8413 -8.6487) (xy 101.8413 -7.6581) (xy 102.3493 -7.6581)
				)
			)
		)
	)
	(footprint ""
		(layer "B.Cu")
		(at 311.130696 -28.942792)
		(property "Reference" "R8D29"
			(at 0 0 0)
			(layer "B.SilkS")
			(hide yes)
			(effects
				(font
					(size 1.27 1.27)
				)
				(justify mirror)
			)
		)
		(property "Value" ""
			(at 0 0 0)
			(layer "B.Fab")
			(effects
				(font
					(size 1.27 1.27)
				)
				(justify mirror)
			)
		)
		(duplicate_pad_numbers_are_jumpers no)
		(fp_poly
			(pts
				(xy 0.2794 -0.1016) (xy -0.2794 -0.1016) (xy -0.2794 0.9906) (xy 0.2794 0.9906)
			)
			(stroke
				(width 0)
				(type default)
			)
			(fill no)
			(layer "B.CrtYd")
		)
		(fp_line
			(start -0.2794 -0.1016)
			(end 0.2794 -0.1016)
			(stroke
				(width 0.1)
				(type default)
			)
			(layer "B.Fab")
		)
		(fp_line
			(start -0.2794 0.9906)
			(end -0.2794 -0.1016)
			(stroke
				(width 0.1)
				(type default)
			)
			(layer "B.Fab")
		)
		(fp_line
			(start 0.2794 -0.1016)
			(end 0.2794 0.9906)
			(stroke
				(width 0.1)
				(type default)
			)
			(layer "B.Fab")
		)
		(fp_line
			(start 0.2794 0.9906)
			(end -0.2794 0.9906)
			(stroke
				(width 0.1)
				(type default)
			)
			(layer "B.Fab")
		)
		(pad "1" smd rect
			(at 0 0 180)
			(size 0.508 0.508)
			(layers "B.Cu" "B.Mask" "B.Paste")
			(net "P3V3_STBY")
		)
		(pad "2" smd rect
			(at 0 0.889 180)
			(size 0.508 0.508)
			(layers "B.Cu" "B.Mask" "B.Paste")
			(net "IRQ_DIMM_SAVE_LVT3")
		)
		(zone
			(layer "B.Cu")
			(hatch none 0.5)
			(connect_pads
				(clearance 0)
			)
			(min_thickness 0.25)
			(keepout
				(tracks allowed)
				(vias not_allowed)
				(pads allowed)
				(copperpour not_allowed)
				(footprints allowed)
			)
			(placement
				(enabled no)
				(sheetname "")
			)
			(fill
				(thermal_gap 0.5)
				(thermal_bridge_width 0.5)
				(island_removal_mode 0)
			)
			(polygon
				(pts
					(xy 311.384696 -28.688792) (xy 310.876696 -28.688792) (xy 310.876696 -28.307792) (xy 311.384696 -28.307792)
				)
			)
		)
		(zone
			(layer "B.Cu")
			(hatch none 0.5)
			(connect_pads
				(clearance 0)
			)
			(min_thickness 0.25)
			(keepout
				(tracks not_allowed)
				(vias allowed)
				(pads allowed)
				(copperpour not_allowed)
				(footprints allowed)
			)
			(placement
				(enabled no)
				(sheetname "")
			)
			(fill
				(thermal_gap 0.5)
				(thermal_bridge_width 0.5)
				(island_removal_mode 0)
			)
			(polygon
				(pts
					(xy 311.384696 -28.307792) (xy 310.876696 -28.307792) (xy 310.876696 -28.688792) (xy 311.384696 -28.688792)
				)
			)
		)
	)
	(footprint ""
		(layer "B.Cu")
		(at 387.604 -87.3125 180)
		(property "Reference" "R3N11"
			(at 0 0 0)
			(layer "B.SilkS")
			(hide yes)
			(effects
				(font
					(size 1.27 1.27)
				)
				(justify mirror)
			)
		)
		(property "Value" ""
			(at 0 0 0)
			(layer "B.Fab")
			(effects
				(font
					(size 1.27 1.27)
				)
				(justify mirror)
			)
		)
		(duplicate_pad_numbers_are_jumpers no)
		(fp_poly
			(pts
				(xy 0.2794 -0.1016) (xy -0.2794 -0.1016) (xy -0.2794 0.9906) (xy 0.2794 0.9906)
			)
			(stroke
				(width 0)
				(type default)
			)
			(fill no)
			(layer "B.CrtYd")
		)
		(fp_line
			(start 0.2794 0.9906)
			(end -0.2794 0.9906)
			(stroke
				(width 0.1)
				(type default)
			)
			(layer "B.Fab")
		)
		(fp_line
			(start 0.2794 -0.1016)
			(end 0.2794 0.9906)
			(stroke
				(width 0.1)
				(type default)
			)
			(layer "B.Fab")
		)
		(fp_line
			(start -0.2794 0.9906)
			(end -0.2794 -0.1016)
			(stroke
				(width 0.1)
				(type default)
			)
			(layer "B.Fab")
		)
		(fp_line
			(start -0.2794 -0.1016)
			(end 0.2794 -0.1016)
			(stroke
				(width 0.1)
				(type default)
			)
			(layer "B.Fab")
		)
		(pad "1" smd rect
			(at 0 0)
			(size 0.508 0.508)
			(layers "B.Cu" "B.Mask" "B.Paste")
			(net "P3V3_STBY")
		)
		(pad "2" smd rect
			(at 0 0.889)
			(size 0.508 0.508)
			(layers "B.Cu" "B.Mask" "B.Paste")
			(net "FM_MP_PS_REDUNDANT_LOST_N")
		)
		(zone
			(layer "B.Cu")
			(hatch none 0.5)
			(connect_pads
				(clearance 0)
			)
			(min_thickness 0.25)
			(keepout
				(tracks not_allowed)
				(vias allowed)
				(pads allowed)
				(copperpour not_allowed)
				(footprints allowed)
			)
			(placement
				(enabled no)
				(sheetname "")
			)
			(fill
				(thermal_gap 0.5)
				(thermal_bridge_width 0.5)
				(island_removal_mode 0)
			)
			(polygon
				(pts
					(xy 387.35 -87.9475) (xy 387.858 -87.9475) (xy 387.858 -87.5665) (xy 387.35 -87.5665)
				)
			)
		)
		(zone
			(layer "B.Cu")
			(hatch none 0.5)
			(connect_pads
				(clearance 0)
			)
			(min_thickness 0.25)
			(keepout
				(tracks allowed)
				(vias not_allowed)
				(pads allowed)
				(copperpour not_allowed)
				(footprints allowed)
			)
			(placement
				(enabled no)
				(sheetname "")
			)
			(fill
				(thermal_gap 0.5)
				(thermal_bridge_width 0.5)
				(island_removal_mode 0)
			)
			(polygon
				(pts
					(xy 387.35 -87.5665) (xy 387.858 -87.5665) (xy 387.858 -87.9475) (xy 387.35 -87.9475)
				)
			)
		)
	)
)
